(
  (version 16.5)
  (tool
    (creator "conceptHDL")
    (last "conceptHDL")
  )
  (library "mstr_symbols")
  (design "p5v"
    (lastIds
      (lastNetId 4)
    )
    (nets
      ("N1" "g" -1 -1 1 3)
      ("N2" "page1_g" -1 -1 0 )
      ("N4" "page1_p5v" -1 -1 0 )
      ("N3" "p5v" -1 -1 2 )
    )

    (alias
      ("N2" -1 -1 "N1" -1 -1)
      ("N4" -1 -1 "N2" -1 -1)
      ("N4" -1 -1 "N3" -1 -1)
    )

  )
)
